# T6G (Grand Teton) — schematic netlist excerpt (pin names and nets, part order shuffled) for the footprints in the layout excerpt that follows; sources: Cadence DE-HDL packaged netlist, KiCad conversion of 04192023_DAF0TMB3IC0_F0TG_MB_C_brd_V02_OCP.brd

U8  74LVC2G07DW7  74LVC2G07DW-7 IC  pkg SOT363_0-65_2X1-25XC  page 134
  \1a\  = OCP_SFF_PRSNT2_R_N
  GND  = GND
  \2a\  = OCP_SFF_PRSNT3_R_N
  \2y\  = HP_LVC3_OCP_V3_1_PRSNT2_N_R
  VCC  = P3V3_AUX
  \1y\  = HP_LVC3_OCP_V3_1_PRSNT2_N_R

PR6550  Q_RES  0 5% CHIP  pkg 0402LF  page 363 : A = P5V_AUX ; B = P0V9_RETIMER_CPU0_PVCC

(kicad_pcb
	(version 20260206)
	(generator "pcbnew")
	(generator_version "10.0")
	(general
		(thickness 1.6)
		(legacy_teardrops no)
	)
	(paper "A4")
	(title_block
		(title "04192023_DAF0TMB3IC0_F0TG_MB_C_brd_V02_OCP.brd")
		(comment 1 "Grand Teton / footprints 2625-2626 of 8354")
	)
	(layers
		(0 "F.Cu" signal "TOP")
		(4 "In1.Cu" signal "GND")
		(6 "In2.Cu" signal "IN1")
		(8 "In3.Cu" signal "GND1")
		(10 "In4.Cu" signal "IN2")
		(12 "In5.Cu" signal "GND2")
		(14 "In6.Cu" signal "IN3")
		(16 "In7.Cu" signal "GND3")
		(18 "In8.Cu" signal "VCC")
		(20 "In9.Cu" signal "VCC1")
		(22 "In10.Cu" signal "GND4")
		(24 "In11.Cu" signal "IN4")
		(26 "In12.Cu" signal "GND5")
		(28 "In13.Cu" signal "IN5")
		(30 "In14.Cu" signal "GND6")
		(32 "In15.Cu" signal "IN6")
		(34 "In16.Cu" signal "GND7")
		(2 "B.Cu" signal "BOTTOM")
		(9 "F.Adhes" user "F.Adhesive")
		(11 "B.Adhes" user "B.Adhesive")
		(13 "F.Paste" user "Package Geometry/Pastemask Top")
		(15 "B.Paste" user "Package Geometry/Pastemask Bottom")
		(5 "F.SilkS" user "Ref Des/Silkscreen Top")
		(7 "B.SilkS" user "Ref Des/Silkscreen Bottom")
		(1 "F.Mask" user "Board Geometry/Soldermask Top")
		(3 "B.Mask" user "Board Geometry/Soldermask Bottom")
		(17 "Dwgs.User" user "User.Drawings")
		(19 "Cmts.User" user "User.Comments")
		(21 "Eco1.User" user "User.Eco1")
		(23 "Eco2.User" user "User.Eco2")
		(25 "Edge.Cuts" user "Board Geometry/Outline")
		(27 "Margin" user)
		(31 "F.CrtYd" user "Package Geometry/Place Bound Top")
		(29 "B.CrtYd" user "Package Geometry/Place Bound Bottom")
		(35 "F.Fab" user "Ref Des/Assembly Top")
		(33 "B.Fab" user "Ref Des/Assembly Bottom")
	)
	(footprint ""
		(layer "F.Cu")
		(at 439.471308 -405.788622 -90)
		(property "Reference" "PR6550"
			(at 0 0 270)
			(layer "F.SilkS")
			(hide yes)
			(effects
				(font
					(size 1.27 1.27)
				)
			)
		)
		(property "Value" ""
			(at 0 0 270)
			(layer "F.Fab")
			(effects
				(font
					(size 1.27 1.27)
				)
			)
		)
		(duplicate_pad_numbers_are_jumpers no)
		(fp_line
			(start -0.7874 0.4064)
			(end -0.7874 -0.4064)
			(stroke
				(width 0.1524)
				(type default)
			)
			(layer "F.SilkS")
		)
		(fp_line
			(start 0.7874 0.4064)
			(end -0.7874 0.4064)
			(stroke
				(width 0.1524)
				(type default)
			)
			(layer "F.SilkS")
		)
		(fp_line
			(start -0.7874 -0.4064)
			(end 0.7874 -0.4064)
			(stroke
				(width 0.1524)
				(type default)
			)
			(layer "F.SilkS")
		)
		(fp_line
			(start 0.7874 -0.4064)
			(end 0.7874 0.4064)
			(stroke
				(width 0.1524)
				(type default)
			)
			(layer "F.SilkS")
		)
		(fp_line
			(start -0.67945 0.3048)
			(end -0.67945 -0.305054)
			(stroke
				(width 0.1)
				(type default)
			)
			(layer "F.Fab")
		)
		(fp_line
			(start -0.12065 0.3048)
			(end -0.67945 0.3048)
			(stroke
				(width 0.1)
				(type default)
			)
			(layer "F.Fab")
		)
		(fp_line
			(start 0.120396 0.3048)
			(end 0.120396 0.2794)
			(stroke
				(width 0.1)
				(type default)
			)
			(layer "F.Fab")
		)
		(fp_line
			(start 0.67945 0.3048)
			(end 0.120396 0.3048)
			(stroke
				(width 0.1)
				(type default)
			)
			(layer "F.Fab")
		)
		(fp_line
			(start -0.12065 0.2794)
			(end -0.12065 0.3048)
			(stroke
				(width 0.1)
				(type default)
			)
			(layer "F.Fab")
		)
		(fp_line
			(start 0.120396 0.2794)
			(end -0.12065 0.2794)
			(stroke
				(width 0.1)
				(type default)
			)
			(layer "F.Fab")
		)
		(fp_line
			(start -0.12065 -0.2794)
			(end 0.12065 -0.2794)
			(stroke
				(width 0.1)
				(type default)
			)
			(layer "F.Fab")
		)
		(fp_line
			(start 0.12065 -0.2794)
			(end 0.12065 -0.3048)
			(stroke
				(width 0.1)
				(type default)
			)
			(layer "F.Fab")
		)
		(fp_line
			(start 0.12065 -0.3048)
			(end 0.67945 -0.3048)
			(stroke
				(width 0.1)
				(type default)
			)
			(layer "F.Fab")
		)
		(fp_line
			(start 0.67945 -0.3048)
			(end 0.67945 0.3048)
			(stroke
				(width 0.1)
				(type default)
			)
			(layer "F.Fab")
		)
		(fp_line
			(start -0.67945 -0.305054)
			(end -0.12065 -0.305054)
			(stroke
				(width 0.1)
				(type default)
			)
			(layer "F.Fab")
		)
		(fp_line
			(start -0.12065 -0.305054)
			(end -0.12065 -0.2794)
			(stroke
				(width 0.1)
				(type default)
			)
			(layer "F.Fab")
		)
		(pad "1" smd circle
			(at -0.40005 0 270)
			(size 0 0)
			(layers "F.Cu" "F.Mask" "F.Paste")
			(net "P5V_AUX")
		)
		(pad "2" smd circle
			(at 0.40005 0 270)
			(size 0 0)
			(layers "F.Cu" "F.Mask" "F.Paste")
			(net "P0V9_RETIMER_CPU0_PVCC")
		)
	)
	(footprint ""
		(layer "F.Cu")
		(at 457.687426 -103.646224)
		(property "Reference" "U8"
			(at -2.8321 -1.679448 0)
			(unlocked yes)
			(layer "F.SilkS")
			(effects
				(font
					(size 0.7874 0.5842)
					(thickness 0.1524)
				)
				(justify left)
			)
		)
		(property "Value" ""
			(at 0 0 0)
			(layer "F.Fab")
			(effects
				(font
					(size 1.27 1.27)
				)
			)
		)
		(duplicate_pad_numbers_are_jumpers no)
		(fp_line
			(start -1.38176 -1.100074)
			(end -1.38176 1.100074)
			(stroke
				(width 0.1524)
				(type default)
			)
			(layer "F.SilkS")
		)
		(fp_line
			(start -1.38176 1.100074)
			(end 1.38176 1.100074)
			(stroke
				(width 0.1524)
				(type default)
			)
			(layer "F.SilkS")
		)
		(fp_line
			(start -0.592074 -1.100074)
			(end -1.38176 -1.100074)
			(stroke
				(width 0.1524)
				(type default)
			)
			(layer "F.SilkS")
		)
		(fp_line
			(start 0 -0.508)
			(end -0.592074 -1.100074)
			(stroke
				(width 0.1524)
				(type default)
			)
			(layer "F.SilkS")
		)
		(fp_line
			(start 0.592074 -1.100074)
			(end 0 -0.508)
			(stroke
				(width 0.1524)
				(type default)
			)
			(layer "F.SilkS")
		)
		(fp_line
			(start 1.38176 -1.100074)
			(end 0.592074 -1.100074)
			(stroke
				(width 0.1524)
				(type default)
			)
			(layer "F.SilkS")
		)
		(fp_line
			(start 1.38176 1.100074)
			(end 1.38176 -1.100074)
			(stroke
				(width 0.1524)
				(type default)
			)
			(layer "F.SilkS")
		)
		(fp_poly
			(pts
				(xy -1.9431 -0.429768) (xy -1.9431 -0.870204) (xy -1.50241 -0.649986)
			)
			(stroke
				(width 0)
				(type default)
			)
			(fill yes)
			(layer "F.SilkS")
		)
		(fp_line
			(start -0.674878 -1.100074)
			(end -0.674878 1.100074)
			(stroke
				(width 0.1)
				(type default)
			)
			(layer "F.Fab")
		)
		(fp_line
			(start -0.674878 1.100074)
			(end 0.674878 1.100074)
			(stroke
				(width 0.1)
				(type default)
			)
			(layer "F.Fab")
		)
		(fp_line
			(start 0.674878 -1.100074)
			(end -0.674878 -1.100074)
			(stroke
				(width 0.1)
				(type default)
			)
			(layer "F.Fab")
		)
		(fp_line
			(start 0.674878 1.100074)
			(end 0.674878 -1.100074)
			(stroke
				(width 0.1)
				(type default)
			)
			(layer "F.Fab")
		)
		(fp_poly
			(pts
				(xy -1.9431 -0.870204) (xy -1.50241 -0.649986) (xy -1.9431 -0.429768)
			)
			(stroke
				(width 0)
				(type default)
			)
			(fill yes)
			(layer "F.Fab")
		)
		(pad "1" smd rect
			(at -0.94996 -0.649986 270)
			(size 0.4318 0.6096)
			(layers "F.Cu" "F.Mask" "F.Paste")
			(net "OCP_SFF_PRSNT2_R_N")
		)
		(pad "2" smd rect
			(at -0.94996 0 270)
			(size 0.4318 0.6096)
			(layers "F.Cu" "F.Mask" "F.Paste")
			(net "GND")
		)
		(pad "3" smd rect
			(at -0.94996 0.649986 270)
			(size 0.4318 0.6096)
			(layers "F.Cu" "F.Mask" "F.Paste")
			(net "OCP_SFF_PRSNT3_R_N")
		)
		(pad "4" smd rect
			(at 0.94996 0.649986 270)
			(size 0.4318 0.6096)
			(layers "F.Cu" "F.Mask" "F.Paste")
			(net "HP_LVC3_OCP_V3_1_PRSNT2_N_R")
		)
		(pad "5" smd rect
			(at 0.94996 0 270)
			(size 0.4318 0.6096)
			(layers "F.Cu" "F.Mask" "F.Paste")
			(net "P3V3_AUX")
		)
		(pad "6" smd rect
			(at 0.94996 -0.649986 270)
			(size 0.4318 0.6096)
			(layers "F.Cu" "F.Mask" "F.Paste")
			(net "HP_LVC3_OCP_V3_1_PRSNT2_N_R")
		)
	)
)
